(kicad_pcb
	(version 20260206)
	(generator "pcbnew")
	(generator_version "10.0")
	(general
		(thickness 1.6)
		(legacy_teardrops no)
	)
	(paper "A4")
	(title_block
		(title "04192023_DAF0TMB3IC0_F0TG_MB_C_brd_V02_OCP.brd")
		(comment 1 "Grand Teton / footprints 1601-1607 of 8354")
	)
	(layers
		(0 "F.Cu" signal "TOP")
		(4 "In1.Cu" signal "GND")
		(6 "In2.Cu" signal "IN1")
		(8 "In3.Cu" signal "GND1")
		(10 "In4.Cu" signal "IN2")
		(12 "In5.Cu" signal "GND2")
		(14 "In6.Cu" signal "IN3")
		(16 "In7.Cu" signal "GND3")
		(18 "In8.Cu" signal "VCC")
		(20 "In9.Cu" signal "VCC1")
		(22 "In10.Cu" signal "GND4")
		(24 "In11.Cu" signal "IN4")
		(26 "In12.Cu" signal "GND5")
		(28 "In13.Cu" signal "IN5")
		(30 "In14.Cu" signal "GND6")
		(32 "In15.Cu" signal "IN6")
		(34 "In16.Cu" signal "GND7")
		(2 "B.Cu" signal "BOTTOM")
		(9 "F.Adhes" user "F.Adhesive")
		(11 "B.Adhes" user "B.Adhesive")
		(13 "F.Paste" user "Package Geometry/Pastemask Top")
		(15 "B.Paste" user "Package Geometry/Pastemask Bottom")
		(5 "F.SilkS" user "Ref Des/Silkscreen Top")
		(7 "B.SilkS" user "Ref Des/Silkscreen Bottom")
		(1 "F.Mask" user "Board Geometry/Soldermask Top")
		(3 "B.Mask" user "Board Geometry/Soldermask Bottom")
		(17 "Dwgs.User" user "User.Drawings")
		(19 "Cmts.User" user "User.Comments")
		(21 "Eco1.User" user "User.Eco1")
		(23 "Eco2.User" user "User.Eco2")
		(25 "Edge.Cuts" user "Board Geometry/Outline")
		(27 "Margin" user)
		(31 "F.CrtYd" user "Package Geometry/Place Bound Top")
		(29 "B.CrtYd" user "Package Geometry/Place Bound Bottom")
		(35 "F.Fab" user "Ref Des/Assembly Top")
		(33 "B.Fab" user "Ref Des/Assembly Bottom")
	)
	(footprint ""
		(layer "F.Cu")
		(at 117.895624 -261.255256 180)
		(property "Reference" "C2273"
			(at 0 0 180)
			(layer "F.SilkS")
			(hide yes)
			(effects
				(font
					(size 1.27 1.27)
				)
			)
		)
		(property "Value" ""
			(at 0 0 180)
			(layer "F.Fab")
			(effects
				(font
					(size 1.27 1.27)
				)
			)
		)
		(duplicate_pad_numbers_are_jumpers no)
		(fp_line
			(start 0.7874 0.4064)
			(end -0.7874 0.4064)
			(stroke
				(width 0.1524)
				(type default)
			)
			(layer "F.SilkS")
		)
		(fp_line
			(start 0.7874 -0.4064)
			(end 0.7874 0.4064)
			(stroke
				(width 0.1524)
				(type default)
			)
			(layer "F.SilkS")
		)
		(fp_line
			(start -0.7874 0.4064)
			(end -0.7874 -0.4064)
			(stroke
				(width 0.1524)
				(type default)
			)
			(layer "F.SilkS")
		)
		(fp_line
			(start -0.7874 -0.4064)
			(end 0.7874 -0.4064)
			(stroke
				(width 0.1524)
				(type default)
			)
			(layer "F.SilkS")
		)
		(fp_line
			(start 0.67945 0.3048)
			(end 0.120396 0.3048)
			(stroke
				(width 0.1)
				(type default)
			)
			(layer "F.Fab")
		)
		(fp_line
			(start 0.67945 -0.3048)
			(end 0.67945 0.3048)
			(stroke
				(width 0.1)
				(type default)
			)
			(layer "F.Fab")
		)
		(fp_line
			(start 0.12065 -0.2794)
			(end 0.12065 -0.3048)
			(stroke
				(width 0.1)
				(type default)
			)
			(layer "F.Fab")
		)
		(fp_line
			(start 0.12065 -0.3048)
			(end 0.67945 -0.3048)
			(stroke
				(width 0.1)
				(type default)
			)
			(layer "F.Fab")
		)
		(fp_line
			(start 0.120396 0.3048)
			(end 0.120396 0.2794)
			(stroke
				(width 0.1)
				(type default)
			)
			(layer "F.Fab")
		)
		(fp_line
			(start 0.120396 0.2794)
			(end -0.12065 0.2794)
			(stroke
				(width 0.1)
				(type default)
			)
			(layer "F.Fab")
		)
		(fp_line
			(start -0.12065 0.3048)
			(end -0.67945 0.3048)
			(stroke
				(width 0.1)
				(type default)
			)
			(layer "F.Fab")
		)
		(fp_line
			(start -0.12065 0.2794)
			(end -0.12065 0.3048)
			(stroke
				(width 0.1)
				(type default)
			)
			(layer "F.Fab")
		)
		(fp_line
			(start -0.12065 -0.2794)
			(end 0.12065 -0.2794)
			(stroke
				(width 0.1)
				(type default)
			)
			(layer "F.Fab")
		)
		(fp_line
			(start -0.12065 -0.305054)
			(end -0.12065 -0.2794)
			(stroke
				(width 0.1)
				(type default)
			)
			(layer "F.Fab")
		)
		(fp_line
			(start -0.67945 0.3048)
			(end -0.67945 -0.305054)
			(stroke
				(width 0.1)
				(type default)
			)
			(layer "F.Fab")
		)
		(fp_line
			(start -0.67945 -0.305054)
			(end -0.12065 -0.305054)
			(stroke
				(width 0.1)
				(type default)
			)
			(layer "F.Fab")
		)
		(pad "1" smd circle
			(at -0.40005 0 180)
			(size 0 0)
			(layers "F.Cu" "F.Mask" "F.Paste")
			(net "PVDDCR_SOC_P1")
		)
		(pad "2" smd circle
			(at 0.40005 0 180)
			(size 0 0)
			(layers "F.Cu" "F.Mask" "F.Paste")
			(net "GND")
		)
	)
	(footprint ""
		(layer "F.Cu")
		(at 208.407 -129.54 90)
		(property "Reference" "R569"
			(at 0 0 90)
			(layer "F.SilkS")
			(hide yes)
			(effects
				(font
					(size 1.27 1.27)
				)
			)
		)
		(property "Value" ""
			(at 0 0 90)
			(layer "F.Fab")
			(effects
				(font
					(size 1.27 1.27)
				)
			)
		)
		(duplicate_pad_numbers_are_jumpers no)
		(fp_line
			(start 0.7874 -0.4064)
			(end 0.7874 0.4064)
			(stroke
				(width 0.1524)
				(type default)
			)
			(layer "F.SilkS")
		)
		(fp_line
			(start -0.7874 -0.4064)
			(end 0.7874 -0.4064)
			(stroke
				(width 0.1524)
				(type default)
			)
			(layer "F.SilkS")
		)
		(fp_line
			(start 0.7874 0.4064)
			(end -0.7874 0.4064)
			(stroke
				(width 0.1524)
				(type default)
			)
			(layer "F.SilkS")
		)
		(fp_line
			(start -0.7874 0.4064)
			(end -0.7874 -0.4064)
			(stroke
				(width 0.1524)
				(type default)
			)
			(layer "F.SilkS")
		)
		(fp_line
			(start -0.12065 -0.305054)
			(end -0.12065 -0.2794)
			(stroke
				(width 0.1)
				(type default)
			)
			(layer "F.Fab")
		)
		(fp_line
			(start -0.67945 -0.305054)
			(end -0.12065 -0.305054)
			(stroke
				(width 0.1)
				(type default)
			)
			(layer "F.Fab")
		)
		(fp_line
			(start 0.67945 -0.3048)
			(end 0.67945 0.3048)
			(stroke
				(width 0.1)
				(type default)
			)
			(layer "F.Fab")
		)
		(fp_line
			(start 0.12065 -0.3048)
			(end 0.67945 -0.3048)
			(stroke
				(width 0.1)
				(type default)
			)
			(layer "F.Fab")
		)
		(fp_line
			(start 0.12065 -0.2794)
			(end 0.12065 -0.3048)
			(stroke
				(width 0.1)
				(type default)
			)
			(layer "F.Fab")
		)
		(fp_line
			(start -0.12065 -0.2794)
			(end 0.12065 -0.2794)
			(stroke
				(width 0.1)
				(type default)
			)
			(layer "F.Fab")
		)
		(fp_line
			(start 0.120396 0.2794)
			(end -0.12065 0.2794)
			(stroke
				(width 0.1)
				(type default)
			)
			(layer "F.Fab")
		)
		(fp_line
			(start -0.12065 0.2794)
			(end -0.12065 0.3048)
			(stroke
				(width 0.1)
				(type default)
			)
			(layer "F.Fab")
		)
		(fp_line
			(start 0.67945 0.3048)
			(end 0.120396 0.3048)
			(stroke
				(width 0.1)
				(type default)
			)
			(layer "F.Fab")
		)
		(fp_line
			(start 0.120396 0.3048)
			(end 0.120396 0.2794)
			(stroke
				(width 0.1)
				(type default)
			)
			(layer "F.Fab")
		)
		(fp_line
			(start -0.12065 0.3048)
			(end -0.67945 0.3048)
			(stroke
				(width 0.1)
				(type default)
			)
			(layer "F.Fab")
		)
		(fp_line
			(start -0.67945 0.3048)
			(end -0.67945 -0.305054)
			(stroke
				(width 0.1)
				(type default)
			)
			(layer "F.Fab")
		)
		(pad "1" smd circle
			(at -0.40005 0 90)
			(size 0 0)
			(layers "F.Cu" "F.Mask" "F.Paste")
			(net "SW_P3V3_EN_ISO_R")
		)
		(pad "2" smd circle
			(at 0.40005 0 90)
			(size 0 0)
			(layers "F.Cu" "F.Mask" "F.Paste")
			(net "SW_P3V3_EN_ISO")
		)
	)
	(footprint ""
		(layer "F.Cu")
		(at 324.168262 -402.7424 -90)
		(property "Reference" "R970"
			(at 0 0 270)
			(layer "F.SilkS")
			(hide yes)
			(effects
				(font
					(size 1.27 1.27)
				)
			)
		)
		(property "Value" ""
			(at 0 0 270)
			(layer "F.Fab")
			(effects
				(font
					(size 1.27 1.27)
				)
			)
		)
		(duplicate_pad_numbers_are_jumpers no)
		(fp_line
			(start -0.32512 0.175006)
			(end -0.32512 -0.175006)
			(stroke
				(width 0.1)
				(type default)
			)
			(layer "F.Fab")
		)
		(fp_line
			(start 0.32512 0.175006)
			(end -0.32512 0.175006)
			(stroke
				(width 0.1)
				(type default)
			)
			(layer "F.Fab")
		)
		(fp_line
			(start -0.32512 -0.175006)
			(end 0.32512 -0.175006)
			(stroke
				(width 0.1)
				(type default)
			)
			(layer "F.Fab")
		)
		(fp_line
			(start 0.32512 -0.175006)
			(end 0.32512 0.175006)
			(stroke
				(width 0.1)
				(type default)
			)
			(layer "F.Fab")
		)
		(pad "1" smd rect
			(at -0.2667 0 270)
			(size 0.3048 0.381)
			(layers "F.Cu" "F.Mask" "F.Paste")
			(net "RST_RT_CPU0_P0_PERST_R_N")
		)
		(pad "2" smd rect
			(at 0.2667 0 90)
			(size 0.3048 0.381)
			(layers "F.Cu" "F.Mask" "F.Paste")
			(net "GND")
		)
	)
	(footprint ""
		(layer "F.Cu")
		(at 39.15029 -426.563536)
		(property "Reference" "C1868"
			(at 0 0 0)
			(layer "F.SilkS")
			(hide yes)
			(effects
				(font
					(size 1.27 1.27)
				)
			)
		)
		(property "Value" ""
			(at 0 0 0)
			(layer "F.Fab")
			(effects
				(font
					(size 1.27 1.27)
				)
			)
		)
		(duplicate_pad_numbers_are_jumpers no)
		(fp_line
			(start -0.7874 -0.4064)
			(end 0.7874 -0.4064)
			(stroke
				(width 0.1524)
				(type default)
			)
			(layer "F.SilkS")
		)
		(fp_line
			(start -0.33909 0.4064)
			(end -0.7874 0.4064)
			(stroke
				(width 0.1524)
				(type default)
			)
			(layer "F.SilkS")
		)
		(fp_line
			(start 0.7874 -0.4064)
			(end 0.7874 0.275336)
			(stroke
				(width 0.1524)
				(type default)
			)
			(layer "F.SilkS")
		)
		(fp_line
			(start -0.6858 -0.3048)
			(end -0.1016 -0.3048)
			(stroke
				(width 0.1)
				(type default)
			)
			(layer "F.Fab")
		)
		(fp_line
			(start -0.6858 0.3048)
			(end -0.6858 -0.3048)
			(stroke
				(width 0.1)
				(type default)
			)
			(layer "F.Fab")
		)
		(fp_line
			(start -0.1016 -0.3048)
			(end -0.1016 -0.2794)
			(stroke
				(width 0.1)
				(type default)
			)
			(layer "F.Fab")
		)
		(fp_line
			(start -0.1016 -0.2794)
			(end 0.1016 -0.2794)
			(stroke
				(width 0.1)
				(type default)
			)
			(layer "F.Fab")
		)
		(fp_line
			(start -0.1016 0.2794)
			(end -0.1016 0.3048)
			(stroke
				(width 0.1)
				(type default)
			)
			(layer "F.Fab")
		)
		(fp_line
			(start -0.1016 0.3048)
			(end -0.6858 0.3048)
			(stroke
				(width 0.1)
				(type default)
			)
			(layer "F.Fab")
		)
		(fp_line
			(start 0.1016 -0.3048)
			(end 0.6858 -0.3048)
			(stroke
				(width 0.1)
				(type default)
			)
			(layer "F.Fab")
		)
		(fp_line
			(start 0.1016 -0.2794)
			(end 0.1016 -0.3048)
			(stroke
				(width 0.1)
				(type default)
			)
			(layer "F.Fab")
		)
		(fp_line
			(start 0.1016 0.2794)
			(end -0.1016 0.2794)
			(stroke
				(width 0.1)
				(type default)
			)
			(layer "F.Fab")
		)
		(fp_line
			(start 0.1016 0.3048)
			(end 0.1016 0.2794)
			(stroke
				(width 0.1)
				(type default)
			)
			(layer "F.Fab")
		)
		(fp_line
			(start 0.6858 -0.3048)
			(end 0.6858 0.3048)
			(stroke
				(width 0.1)
				(type default)
			)
			(layer "F.Fab")
		)
		(fp_line
			(start 0.6858 0.3048)
			(end 0.1016 0.3048)
			(stroke
				(width 0.1)
				(type default)
			)
			(layer "F.Fab")
		)
		(pad "1" smd rect
			(at -0.40005 0 180)
			(size 0.4572 0.508)
			(layers "F.Cu" "F.Mask" "F.Paste")
			(net "P2E_MB_BMC_RX_BUF_C_DP<0>")
		)
		(pad "2" smd rect
			(at 0.40005 0 180)
			(size 0.4572 0.508)
			(layers "F.Cu" "F.Mask" "F.Paste")
			(net "P2E_MB_BMC_RX_BUF_DP<0>")
		)
	)
	(footprint ""
		(layer "F.Cu")
		(at 366.36579 -393.04468)
		(property "Reference" "R1113"
			(at 0 0 0)
			(layer "F.SilkS")
			(hide yes)
			(effects
				(font
					(size 1.27 1.27)
				)
			)
		)
		(property "Value" ""
			(at 0 0 0)
			(layer "F.Fab")
			(effects
				(font
					(size 1.27 1.27)
				)
			)
		)
		(duplicate_pad_numbers_are_jumpers no)
		(fp_line
			(start -0.32512 -0.175006)
			(end 0.32512 -0.175006)
			(stroke
				(width 0.1)
				(type default)
			)
			(layer "F.Fab")
		)
		(fp_line
			(start -0.32512 0.175006)
			(end -0.32512 -0.175006)
			(stroke
				(width 0.1)
				(type default)
			)
			(layer "F.Fab")
		)
		(fp_line
			(start 0.32512 -0.175006)
			(end 0.32512 0.175006)
			(stroke
				(width 0.1)
				(type default)
			)
			(layer "F.Fab")
		)
		(fp_line
			(start 0.32512 0.175006)
			(end -0.32512 0.175006)
			(stroke
				(width 0.1)
				(type default)
			)
			(layer "F.Fab")
		)
		(pad "1" smd rect
			(at -0.2667 0)
			(size 0.3048 0.381)
			(layers "F.Cu" "F.Mask" "F.Paste")
			(net "GPIO3_RT_CPU0_P3")
		)
		(pad "2" smd rect
			(at 0.2667 0 180)
			(size 0.3048 0.381)
			(layers "F.Cu" "F.Mask" "F.Paste")
			(net "GND")
		)
	)
	(footprint ""
		(layer "F.Cu")
		(at 321.107308 -104.42575)
		(property "Reference" "R1305"
			(at 0 0 0)
			(layer "F.SilkS")
			(hide yes)
			(effects
				(font
					(size 1.27 1.27)
				)
			)
		)
		(property "Value" ""
			(at 0 0 0)
			(layer "F.Fab")
			(effects
				(font
					(size 1.27 1.27)
				)
			)
		)
		(duplicate_pad_numbers_are_jumpers no)
		(fp_line
			(start -0.7874 -0.4064)
			(end 0.7874 -0.4064)
			(stroke
				(width 0.1524)
				(type default)
			)
			(layer "F.SilkS")
		)
		(fp_line
			(start -0.7874 0.4064)
			(end -0.7874 -0.4064)
			(stroke
				(width 0.1524)
				(type default)
			)
			(layer "F.SilkS")
		)
		(fp_line
			(start 0.7874 -0.4064)
			(end 0.7874 0.4064)
			(stroke
				(width 0.1524)
				(type default)
			)
			(layer "F.SilkS")
		)
		(fp_line
			(start 0.7874 0.4064)
			(end -0.7874 0.4064)
			(stroke
				(width 0.1524)
				(type default)
			)
			(layer "F.SilkS")
		)
		(fp_line
			(start -0.67945 -0.305054)
			(end -0.12065 -0.305054)
			(stroke
				(width 0.1)
				(type default)
			)
			(layer "F.Fab")
		)
		(fp_line
			(start -0.67945 0.3048)
			(end -0.67945 -0.305054)
			(stroke
				(width 0.1)
				(type default)
			)
			(layer "F.Fab")
		)
		(fp_line
			(start -0.12065 -0.305054)
			(end -0.12065 -0.2794)
			(stroke
				(width 0.1)
				(type default)
			)
			(layer "F.Fab")
		)
		(fp_line
			(start -0.12065 -0.2794)
			(end 0.12065 -0.2794)
			(stroke
				(width 0.1)
				(type default)
			)
			(layer "F.Fab")
		)
		(fp_line
			(start -0.12065 0.2794)
			(end -0.12065 0.3048)
			(stroke
				(width 0.1)
				(type default)
			)
			(layer "F.Fab")
		)
		(fp_line
			(start -0.12065 0.3048)
			(end -0.67945 0.3048)
			(stroke
				(width 0.1)
				(type default)
			)
			(layer "F.Fab")
		)
		(fp_line
			(start 0.120396 0.2794)
			(end -0.12065 0.2794)
			(stroke
				(width 0.1)
				(type default)
			)
			(layer "F.Fab")
		)
		(fp_line
			(start 0.120396 0.3048)
			(end 0.120396 0.2794)
			(stroke
				(width 0.1)
				(type default)
			)
			(layer "F.Fab")
		)
		(fp_line
			(start 0.12065 -0.3048)
			(end 0.67945 -0.3048)
			(stroke
				(width 0.1)
				(type default)
			)
			(layer "F.Fab")
		)
		(fp_line
			(start 0.12065 -0.2794)
			(end 0.12065 -0.3048)
			(stroke
				(width 0.1)
				(type default)
			)
			(layer "F.Fab")
		)
		(fp_line
			(start 0.67945 -0.3048)
			(end 0.67945 0.3048)
			(stroke
				(width 0.1)
				(type default)
			)
			(layer "F.Fab")
		)
		(fp_line
			(start 0.67945 0.3048)
			(end 0.120396 0.3048)
			(stroke
				(width 0.1)
				(type default)
			)
			(layer "F.Fab")
		)
		(pad "1" smd circle
			(at -0.40005 0)
			(size 0 0)
			(layers "F.Cu" "F.Mask" "F.Paste")
			(net "GND")
		)
		(pad "2" smd circle
			(at 0.40005 0)
			(size 0 0)
			(layers "F.Cu" "F.Mask" "F.Paste")
			(net "INA230_8_A1")
		)
	)
	(footprint ""
		(layer "F.Cu")
		(at 56.858408 -36.75634 180)
		(property "Reference" "R1521"
			(at 0 0 180)
			(layer "F.SilkS")
			(hide yes)
			(effects
				(font
					(size 1.27 1.27)
				)
			)
		)
		(property "Value" ""
			(at 0 0 180)
			(layer "F.Fab")
			(effects
				(font
					(size 1.27 1.27)
				)
			)
		)
		(duplicate_pad_numbers_are_jumpers no)
		(fp_line
			(start 0.7874 0.4064)
			(end -0.7874 0.4064)
			(stroke
				(width 0.1524)
				(type default)
			)
			(layer "F.SilkS")
		)
		(fp_line
			(start 0.7874 -0.4064)
			(end 0.7874 0.4064)
			(stroke
				(width 0.1524)
				(type default)
			)
			(layer "F.SilkS")
		)
		(fp_line
			(start -0.7874 0.4064)
			(end -0.7874 -0.4064)
			(stroke
				(width 0.1524)
				(type default)
			)
			(layer "F.SilkS")
		)
		(fp_line
			(start -0.7874 -0.4064)
			(end 0.7874 -0.4064)
			(stroke
				(width 0.1524)
				(type default)
			)
			(layer "F.SilkS")
		)
		(fp_line
			(start 0.67945 0.3048)
			(end 0.120396 0.3048)
			(stroke
				(width 0.1)
				(type default)
			)
			(layer "F.Fab")
		)
		(fp_line
			(start 0.67945 -0.3048)
			(end 0.67945 0.3048)
			(stroke
				(width 0.1)
				(type default)
			)
			(layer "F.Fab")
		)
		(fp_line
			(start 0.12065 -0.2794)
			(end 0.12065 -0.3048)
			(stroke
				(width 0.1)
				(type default)
			)
			(layer "F.Fab")
		)
		(fp_line
			(start 0.12065 -0.3048)
			(end 0.67945 -0.3048)
			(stroke
				(width 0.1)
				(type default)
			)
			(layer "F.Fab")
		)
		(fp_line
			(start 0.120396 0.3048)
			(end 0.120396 0.2794)
			(stroke
				(width 0.1)
				(type default)
			)
			(layer "F.Fab")
		)
		(fp_line
			(start 0.120396 0.2794)
			(end -0.12065 0.2794)
			(stroke
				(width 0.1)
				(type default)
			)
			(layer "F.Fab")
		)
		(fp_line
			(start -0.12065 0.3048)
			(end -0.67945 0.3048)
			(stroke
				(width 0.1)
				(type default)
			)
			(layer "F.Fab")
		)
		(fp_line
			(start -0.12065 0.2794)
			(end -0.12065 0.3048)
			(stroke
				(width 0.1)
				(type default)
			)
			(layer "F.Fab")
		)
		(fp_line
			(start -0.12065 -0.2794)
			(end 0.12065 -0.2794)
			(stroke
				(width 0.1)
				(type default)
			)
			(layer "F.Fab")
		)
		(fp_line
			(start -0.12065 -0.305054)
			(end -0.12065 -0.2794)
			(stroke
				(width 0.1)
				(type default)
			)
			(layer "F.Fab")
		)
		(fp_line
			(start -0.67945 0.3048)
			(end -0.67945 -0.305054)
			(stroke
				(width 0.1)
				(type default)
			)
			(layer "F.Fab")
		)
		(fp_line
			(start -0.67945 -0.305054)
			(end -0.12065 -0.305054)
			(stroke
				(width 0.1)
				(type default)
			)
			(layer "F.Fab")
		)
		(pad "1" smd circle
			(at -0.40005 0 180)
			(size 0 0)
			(layers "F.Cu" "F.Mask" "F.Paste")
			(net "P12V_OCP_V3_2_BUF_EN_R")
		)
		(pad "2" smd circle
			(at 0.40005 0 180)
			(size 0 0)
			(layers "F.Cu" "F.Mask" "F.Paste")
			(net "P3V3_OCP_EN_2")
		)
	)
)
